(kicad_pcb
	(version 20260206)
	(generator "pcbnew")
	(generator_version "10.0")
	(general
		(thickness 1.6)
		(legacy_teardrops no)
	)
	(paper "A4")
	(title_block
		(title "peb — Lightning_PEB_BRD.brd")
		(comment 1 "Lightning (Wiwynn / Facebook NVMe JBOF) / footprints 807-813 of 2563")
	)
	(layers
		(0 "F.Cu" signal "TOP")
		(4 "In1.Cu" signal "L2GND")
		(6 "In2.Cu" signal "L3")
		(8 "In3.Cu" signal "L4VCC")
		(10 "In4.Cu" signal "L5VCC")
		(12 "In5.Cu" signal "L6")
		(14 "In6.Cu" signal "L7GND")
		(2 "B.Cu" signal "BOTTOM")
		(9 "F.Adhes" user "F.Adhesive")
		(11 "B.Adhes" user "B.Adhesive")
		(13 "F.Paste" user "Package Geometry/Pastemask Top")
		(15 "B.Paste" user "Package Geometry/Pastemask Bottom")
		(5 "F.SilkS" user "Ref Des/Silkscreen Top")
		(7 "B.SilkS" user "Ref Des/Silkscreen Bottom")
		(1 "F.Mask" user "Board Geometry/Soldermask Top")
		(3 "B.Mask" user "Board Geometry/Soldermask Bottom")
		(17 "Dwgs.User" user "User.Drawings")
		(19 "Cmts.User" user "User.Comments")
		(21 "Eco1.User" user "User.Eco1")
		(23 "Eco2.User" user "User.Eco2")
		(25 "Edge.Cuts" user "Board Geometry/Outline")
		(27 "Margin" user)
		(31 "F.CrtYd" user "Package Geometry/Place Bound Top")
		(29 "B.CrtYd" user "Package Geometry/Place Bound Bottom")
		(35 "F.Fab" user "Ref Des/Assembly Top")
		(33 "B.Fab" user "Ref Des/Assembly Bottom")
	)
	(footprint ""
		(layer "F.Cu")
		(at 142.374874 -90.95232)
		(property "Reference" "PU6"
			(at 0 0 0)
			(layer "F.SilkS")
			(hide yes)
			(effects
				(font
					(size 1.27 1.27)
				)
			)
		)
		(property "Value" "TPS74801DRCR-1-GP-U"
			(at -3.5306 1.3208 0)
			(unlocked yes)
			(layer "F.Fab")
			(hide yes)
			(effects
				(font
					(size 1.016 1.016)
					(thickness 0.1524)
				)
			)
		)
		(property "Device Type" "DFN10G3-G315175H40"
			(at -3.5306 -0.2032 0)
			(unlocked yes)
			(layer "F.Fab")
			(hide yes)
			(effects
				(font
					(size 1.016 1.016)
					(thickness 0.1524)
				)
			)
		)
		(duplicate_pad_numbers_are_jumpers no)
		(fp_line
			(start -2.3876 -2.5146)
			(end -2.3876 -1.7526)
			(stroke
				(width 0.1524)
				(type default)
			)
			(layer "F.SilkS")
		)
		(fp_line
			(start -2.3876 1.7526)
			(end -2.3876 2.5146)
			(stroke
				(width 0.1524)
				(type default)
			)
			(layer "F.SilkS")
		)
		(fp_line
			(start -2.3876 2.5146)
			(end -1.6256 2.5146)
			(stroke
				(width 0.1524)
				(type default)
			)
			(layer "F.SilkS")
		)
		(fp_line
			(start -1.6256 -2.5146)
			(end -2.3876 -2.5146)
			(stroke
				(width 0.1524)
				(type default)
			)
			(layer "F.SilkS")
		)
		(fp_line
			(start -0.9906 -2.794)
			(end -0.9906 -2.286)
			(stroke
				(width 0.1524)
				(type default)
			)
			(layer "F.SilkS")
		)
		(fp_line
			(start 0.9906 2.286)
			(end 0.9906 3.048)
			(stroke
				(width 0.1524)
				(type default)
			)
			(layer "F.SilkS")
		)
		(fp_line
			(start 1.6256 2.5146)
			(end 2.3876 2.5146)
			(stroke
				(width 0.1524)
				(type default)
			)
			(layer "F.SilkS")
		)
		(fp_line
			(start 2.3876 2.5146)
			(end 2.3876 1.7526)
			(stroke
				(width 0.1524)
				(type default)
			)
			(layer "F.SilkS")
		)
		(fp_poly
			(pts
				(xy 1.6256 -2.5146) (xy 2.3876 -2.5146) (xy 2.3876 -1.7526)
			)
			(stroke
				(width 0)
				(type default)
			)
			(fill yes)
			(layer "F.SilkS")
		)
		(fp_rect
			(start -1.4986 1.4986)
			(end 1.4986 -1.4986)
			(stroke
				(width 0)
				(type default)
			)
			(fill no)
			(layer "F.CrtYd")
		)
		(fp_poly
			(pts
				(xy -2.3876 2.5146) (xy -2.3876 0.00254) (xy -1.4986 0.00254) (xy -1.4986 1.4986) (xy 1.4986 1.4986)
				(xy 1.4986 -1.4986) (xy -1.4986 -1.4986) (xy -1.4986 -0.00254) (xy -2.3876 -0.00254) (xy -2.3876 -2.5146)
				(xy 2.3876 -2.5146) (xy 2.3876 2.5146)
			)
			(stroke
				(width 0)
				(type default)
			)
			(fill no)
			(layer "F.CrtYd")
		)
		(fp_rect
			(start -2.3876 2.5146)
			(end 2.3876 -2.5146)
			(stroke
				(width 0)
				(type default)
			)
			(fill no)
			(layer "F.Fab")
		)
		(pad "1" smd rect
			(at 0.99949 -1.5494)
			(size 0.3048 0.9144)
			(layers "F.Cu" "F.Mask" "F.Paste")
			(net "VR_P1V8_STBY_IN")
		)
		(pad "2" smd rect
			(at 0.50038 -1.5494)
			(size 0.3048 0.9144)
			(layers "F.Cu" "F.Mask" "F.Paste")
			(net "VR_P1V8_STBY_IN")
		)
		(pad "3" smd rect
			(at 0 -1.5494)
			(size 0.3048 0.9144)
			(layers "F.Cu" "F.Mask" "F.Paste")
			(net "PWRGD_P1V8_STBY")
		)
		(pad "4" smd rect
			(at -0.50038 -1.5494)
			(size 0.3048 0.9144)
			(layers "F.Cu" "F.Mask" "F.Paste")
			(net "VR_P1V8_STBY_BIAS")
		)
		(pad "5" smd rect
			(at -0.99949 -1.5494)
			(size 0.3048 0.9144)
			(layers "F.Cu" "F.Mask" "F.Paste")
			(net "VR_P1V8_STBY_EN_R")
		)
		(pad "6" smd rect
			(at -0.99949 1.5494)
			(size 0.3048 0.9144)
			(layers "F.Cu" "F.Mask" "F.Paste")
			(net "GND")
		)
		(pad "7" smd rect
			(at -0.50038 1.5494)
			(size 0.3048 0.9144)
			(layers "F.Cu" "F.Mask" "F.Paste")
			(net "VR_P1V8_STBY_SS_C")
		)
		(pad "8" smd rect
			(at 0 1.5494)
			(size 0.3048 0.9144)
			(layers "F.Cu" "F.Mask" "F.Paste")
			(net "VR_P1V8_STBY_FB")
		)
		(pad "9" smd rect
			(at 0.50038 1.5494)
			(size 0.3048 0.9144)
			(layers "F.Cu" "F.Mask" "F.Paste")
			(net "P1V8_PWR")
		)
		(pad "10" smd rect
			(at 0.99949 1.5494)
			(size 0.3048 0.9144)
			(layers "F.Cu" "F.Mask" "F.Paste")
			(net "P1V8_PWR")
		)
		(pad "11" smd custom
			(at 0 0)
			(size 0.4318 0.4318)
			(layers "F.Cu" "F.Mask" "F.Paste")
			(net "GND")
			(options
				(clearance outline)
				(anchor circle)
			)
			(primitives
				(gr_poly
					(pts
						(xy -1.2446 0.8636) (xy -1.2446 0.3937) (xy -1.8796 0.3937) (xy -1.8796 0.1143) (xy -1.2446 0.1143)
						(xy -1.2446 -0.1143) (xy -1.8796 -0.1143) (xy -1.8796 -0.3937) (xy -1.2446 -0.3937) (xy -1.2446 -0.8636)
						(xy 1.2446 -0.8636) (xy 1.2446 -0.3937) (xy 1.8796 -0.3937) (xy 1.8796 -0.1143) (xy 1.2446 -0.1143)
						(xy 1.2446 0.1143) (xy 1.8796 0.1143) (xy 1.8796 0.3937) (xy 1.2446 0.3937) (xy 1.2446 0.8636)
					)
					(width 0)
					(fill yes)
				)
			)
		)
	)
	(footprint ""
		(layer "F.Cu")
		(at 131.470146 -59.750198 180)
		(property "Reference" "R616"
			(at 0 0 180)
			(layer "F.SilkS")
			(hide yes)
			(effects
				(font
					(size 1.27 1.27)
				)
			)
		)
		(property "Value" "100KR2F-L1-GP"
			(at 0.064008 -3.993896 180)
			(unlocked yes)
			(layer "F.Fab")
			(hide yes)
			(effects
				(font
					(size 1.016 1.016)
					(thickness 0.1524)
				)
			)
		)
		(property "Device Type" "R402H16"
			(at 0.064008 -5.517896 180)
			(unlocked yes)
			(layer "F.Fab")
			(hide yes)
			(effects
				(font
					(size 1.016 1.016)
					(thickness 0.1524)
				)
			)
		)
		(duplicate_pad_numbers_are_jumpers no)
		(fp_line
			(start 0.508 -0.9398)
			(end -0.508 -0.9398)
			(stroke
				(width 0.1524)
				(type default)
			)
			(layer "F.SilkS")
		)
		(fp_line
			(start -0.508 -0.9398)
			(end -0.508 0.9398)
			(stroke
				(width 0.1524)
				(type default)
			)
			(layer "F.SilkS")
		)
		(fp_rect
			(start -0.508 0.9398)
			(end 0.508 -0.9398)
			(stroke
				(width 0)
				(type default)
			)
			(fill no)
			(layer "F.CrtYd")
		)
		(fp_rect
			(start -0.508 0.9398)
			(end 0.508 -0.9398)
			(stroke
				(width 0)
				(type default)
			)
			(fill no)
			(layer "F.Fab")
		)
		(pad "1" smd custom
			(at 0 -0.4445 180)
			(size 0.1397 0.1397)
			(layers "F.Cu" "F.Mask" "F.Paste")
			(net "DUT_VDDO")
			(options
				(clearance outline)
				(anchor circle)
			)
			(primitives
				(gr_poly
					(pts
						(arc
							(start -0.1778 -0.2794)
							(mid -0.249642 -0.249642)
							(end -0.2794 -0.1778)
						)
						(arc
							(start -0.2794 0.1778)
							(mid -0.249642 0.249642)
							(end -0.1778 0.2794)
						)
						(arc
							(start 0.1778 0.2794)
							(mid 0.249642 0.249642)
							(end 0.2794 0.1778)
						)
						(arc
							(start 0.2794 -0.1778)
							(mid 0.249642 -0.249642)
							(end 0.1778 -0.2794)
						)
					)
					(width 0)
					(fill yes)
				)
			)
		)
		(pad "2" smd custom
			(at 0 0.4445 180)
			(size 0.1397 0.1397)
			(layers "F.Cu" "F.Mask" "F.Paste")
			(net "SPI_CSB0_0")
			(options
				(clearance outline)
				(anchor circle)
			)
			(primitives
				(gr_poly
					(pts
						(arc
							(start -0.1778 -0.2794)
							(mid -0.249642 -0.249642)
							(end -0.2794 -0.1778)
						)
						(arc
							(start -0.2794 0.1778)
							(mid -0.249642 0.249642)
							(end -0.1778 0.2794)
						)
						(arc
							(start 0.1778 0.2794)
							(mid 0.249642 0.249642)
							(end 0.2794 0.1778)
						)
						(arc
							(start 0.2794 -0.1778)
							(mid 0.249642 -0.249642)
							(end 0.1778 -0.2794)
						)
					)
					(width 0)
					(fill yes)
				)
			)
		)
	)
	(footprint ""
		(layer "F.Cu")
		(at 322.707 -86.487 180)
		(property "Reference" "R559"
			(at 0 0 180)
			(layer "F.SilkS")
			(hide yes)
			(effects
				(font
					(size 1.27 1.27)
				)
			)
		)
		(property "Value" "10KR2F-2-GP"
			(at 0.064008 -3.993896 180)
			(unlocked yes)
			(layer "F.Fab")
			(hide yes)
			(effects
				(font
					(size 1.016 1.016)
					(thickness 0.1524)
				)
			)
		)
		(property "Device Type" "R402H16"
			(at 0.064008 -5.517896 180)
			(unlocked yes)
			(layer "F.Fab")
			(hide yes)
			(effects
				(font
					(size 1.016 1.016)
					(thickness 0.1524)
				)
			)
		)
		(duplicate_pad_numbers_are_jumpers no)
		(fp_line
			(start 0.508 -0.9398)
			(end -0.508 -0.9398)
			(stroke
				(width 0.1524)
				(type default)
			)
			(layer "F.SilkS")
		)
		(fp_line
			(start -0.508 -0.9398)
			(end -0.508 0.9398)
			(stroke
				(width 0.1524)
				(type default)
			)
			(layer "F.SilkS")
		)
		(fp_rect
			(start -0.508 0.9398)
			(end 0.508 -0.9398)
			(stroke
				(width 0)
				(type default)
			)
			(fill no)
			(layer "F.CrtYd")
		)
		(fp_rect
			(start -0.508 0.9398)
			(end 0.508 -0.9398)
			(stroke
				(width 0)
				(type default)
			)
			(fill no)
			(layer "F.Fab")
		)
		(pad "1" smd custom
			(at 0 -0.4445 180)
			(size 0.1397 0.1397)
			(layers "F.Cu" "F.Mask" "F.Paste")
			(net "P3V3_STBY")
			(options
				(clearance outline)
				(anchor circle)
			)
			(primitives
				(gr_poly
					(pts
						(arc
							(start -0.1778 -0.2794)
							(mid -0.249642 -0.249642)
							(end -0.2794 -0.1778)
						)
						(arc
							(start -0.2794 0.1778)
							(mid -0.249642 0.249642)
							(end -0.1778 0.2794)
						)
						(arc
							(start 0.1778 0.2794)
							(mid 0.249642 0.249642)
							(end 0.2794 0.1778)
						)
						(arc
							(start 0.2794 -0.1778)
							(mid 0.249642 -0.249642)
							(end 0.1778 -0.2794)
						)
					)
					(width 0)
					(fill yes)
				)
			)
		)
		(pad "2" smd custom
			(at 0 0.4445 180)
			(size 0.1397 0.1397)
			(layers "F.Cu" "F.Mask" "F.Paste")
			(net "IOEXP_PMC1_AD2")
			(options
				(clearance outline)
				(anchor circle)
			)
			(primitives
				(gr_poly
					(pts
						(arc
							(start -0.1778 -0.2794)
							(mid -0.249642 -0.249642)
							(end -0.2794 -0.1778)
						)
						(arc
							(start -0.2794 0.1778)
							(mid -0.249642 0.249642)
							(end -0.1778 0.2794)
						)
						(arc
							(start 0.1778 0.2794)
							(mid 0.249642 0.249642)
							(end 0.2794 0.1778)
						)
						(arc
							(start 0.2794 -0.1778)
							(mid 0.249642 -0.249642)
							(end 0.1778 -0.2794)
						)
					)
					(width 0)
					(fill yes)
				)
			)
		)
	)
	(footprint ""
		(layer "F.Cu")
		(at 335.592166 -212.420454 180)
		(property "Reference" "C58"
			(at 0 0 180)
			(layer "F.SilkS")
			(hide yes)
			(effects
				(font
					(size 1.27 1.27)
				)
			)
		)
		(property "Value" "SCD22U10V2KX-1GP"
			(at 1.1811 -2.7051 180)
			(unlocked yes)
			(layer "F.Fab")
			(hide yes)
			(effects
				(font
					(size 1.016 1.016)
					(thickness 0.1524)
				)
			)
		)
		(property "Device Type" "C402H22"
			(at 1.1811 -4.2291 180)
			(unlocked yes)
			(layer "F.Fab")
			(hide yes)
			(effects
				(font
					(size 1.016 1.016)
					(thickness 0.1524)
				)
			)
		)
		(duplicate_pad_numbers_are_jumpers no)
		(fp_rect
			(start -0.4318 0.9525)
			(end 0.4318 -0.9525)
			(stroke
				(width 0)
				(type default)
			)
			(fill no)
			(layer "F.CrtYd")
		)
		(fp_rect
			(start -0.4318 0.9525)
			(end 0.4318 -0.9525)
			(stroke
				(width 0)
				(type default)
			)
			(fill no)
			(layer "F.Fab")
		)
		(pad "1" smd custom
			(at 0 -0.4445 180)
			(size 0.1524 0.1524)
			(layers "F.Cu" "F.Mask" "F.Paste")
			(net "PCIE_TX_CAP_P18")
			(options
				(clearance outline)
				(anchor circle)
			)
			(primitives
				(gr_poly
					(pts
						(arc
							(start 0.3048 -0.2032)
							(mid 0.275042 -0.275042)
							(end 0.2032 -0.3048)
						)
						(arc
							(start -0.2032 -0.3048)
							(mid -0.275042 -0.275042)
							(end -0.3048 -0.2032)
						)
						(arc
							(start -0.3048 0.2032)
							(mid -0.275042 0.275042)
							(end -0.2032 0.3048)
						)
						(arc
							(start 0.2032 0.3048)
							(mid 0.275042 0.275042)
							(end 0.3048 0.2032)
						)
					)
					(width 0)
					(fill yes)
				)
			)
		)
		(pad "2" smd custom
			(at 0 0.4445 180)
			(size 0.1524 0.1524)
			(layers "F.Cu" "F.Mask" "F.Paste")
			(net "PCIE_TX_P18")
			(options
				(clearance outline)
				(anchor circle)
			)
			(primitives
				(gr_poly
					(pts
						(arc
							(start 0.3048 -0.2032)
							(mid 0.275042 -0.275042)
							(end 0.2032 -0.3048)
						)
						(arc
							(start -0.2032 -0.3048)
							(mid -0.275042 -0.275042)
							(end -0.3048 -0.2032)
						)
						(arc
							(start -0.3048 0.2032)
							(mid -0.275042 0.275042)
							(end -0.2032 0.3048)
						)
						(arc
							(start 0.2032 0.3048)
							(mid 0.275042 0.275042)
							(end 0.3048 0.2032)
						)
					)
					(width 0)
					(fill yes)
				)
			)
		)
	)
	(footprint ""
		(layer "F.Cu")
		(at 316.983872 -35.859466 90)
		(property "Reference" "R218"
			(at 0 0 90)
			(layer "F.SilkS")
			(hide yes)
			(effects
				(font
					(size 1.27 1.27)
				)
			)
		)
		(property "Value" "4K7R2F-GP"
			(at 0.064008 -3.993896 90)
			(unlocked yes)
			(layer "F.Fab")
			(hide yes)
			(effects
				(font
					(size 1.016 1.016)
					(thickness 0.1524)
				)
			)
		)
		(property "Device Type" "R402H16"
			(at 0.064008 -5.517896 90)
			(unlocked yes)
			(layer "F.Fab")
			(hide yes)
			(effects
				(font
					(size 1.016 1.016)
					(thickness 0.1524)
				)
			)
		)
		(duplicate_pad_numbers_are_jumpers no)
		(fp_line
			(start 0.508 -0.9398)
			(end -0.508 -0.9398)
			(stroke
				(width 0.1524)
				(type default)
			)
			(layer "F.SilkS")
		)
		(fp_line
			(start -0.508 -0.9398)
			(end -0.508 0.9398)
			(stroke
				(width 0.1524)
				(type default)
			)
			(layer "F.SilkS")
		)
		(fp_rect
			(start -0.508 0.9398)
			(end 0.508 -0.9398)
			(stroke
				(width 0)
				(type default)
			)
			(fill no)
			(layer "F.CrtYd")
		)
		(fp_rect
			(start -0.508 0.9398)
			(end 0.508 -0.9398)
			(stroke
				(width 0)
				(type default)
			)
			(fill no)
			(layer "F.Fab")
		)
		(pad "1" smd custom
			(at 0 -0.4445 90)
			(size 0.1397 0.1397)
			(layers "F.Cu" "F.Mask" "F.Paste")
			(net "CLK_P_8_R")
			(options
				(clearance outline)
				(anchor circle)
			)
			(primitives
				(gr_poly
					(pts
						(arc
							(start -0.1778 -0.2794)
							(mid -0.249642 -0.249642)
							(end -0.2794 -0.1778)
						)
						(arc
							(start -0.2794 0.1778)
							(mid -0.249642 0.249642)
							(end -0.1778 0.2794)
						)
						(arc
							(start 0.1778 0.2794)
							(mid 0.249642 0.249642)
							(end 0.2794 0.1778)
						)
						(arc
							(start 0.2794 -0.1778)
							(mid 0.249642 -0.249642)
							(end 0.1778 -0.2794)
						)
					)
					(width 0)
					(fill yes)
				)
			)
		)
		(pad "2" smd custom
			(at 0 0.4445 90)
			(size 0.1397 0.1397)
			(layers "F.Cu" "F.Mask" "F.Paste")
			(net "GND")
			(options
				(clearance outline)
				(anchor circle)
			)
			(primitives
				(gr_poly
					(pts
						(arc
							(start -0.1778 -0.2794)
							(mid -0.249642 -0.249642)
							(end -0.2794 -0.1778)
						)
						(arc
							(start -0.2794 0.1778)
							(mid -0.249642 0.249642)
							(end -0.1778 0.2794)
						)
						(arc
							(start 0.1778 0.2794)
							(mid 0.249642 0.249642)
							(end 0.2794 0.1778)
						)
						(arc
							(start 0.2794 -0.1778)
							(mid 0.249642 -0.249642)
							(end 0.1778 -0.2794)
						)
					)
					(width 0)
					(fill yes)
				)
			)
		)
	)
	(footprint ""
		(layer "F.Cu")
		(at 39.538148 -68.890642 90)
		(property "Reference" "PG2"
			(at 0 0 90)
			(layer "F.SilkS")
			(hide yes)
			(effects
				(font
					(size 1.27 1.27)
				)
			)
		)
		(property "Value" "GAP-CLOSE-PWR-3-GP"
			(at 0.0254 -6.5786 90)
			(unlocked yes)
			(layer "F.Fab")
			(hide yes)
			(effects
				(font
					(size 1.016 1.016)
					(thickness 0.1524)
				)
			)
		)
		(property "Device Type" "GAP-CLOSE-PWR-3"
			(at 0.0254 -8.255 90)
			(unlocked yes)
			(layer "F.Fab")
			(hide yes)
			(effects
				(font
					(size 1.016 1.016)
					(thickness 0.1524)
				)
			)
		)
		(duplicate_pad_numbers_are_jumpers no)
		(fp_rect
			(start -0.7112 0.4572)
			(end 0.7112 -0.4572)
			(stroke
				(width 0)
				(type default)
			)
			(fill no)
			(layer "F.CrtYd")
		)
		(fp_poly
			(pts
				(xy -0.7112 -0.4572) (xy 0.7112 -0.4572) (xy 0.7112 0.4572) (xy -0.7112 0.4572)
			)
			(stroke
				(width 0)
				(type default)
			)
			(fill no)
			(layer "F.Fab")
		)
		(pad "1" smd rect
			(at -0.3048 0 90)
			(size 0.6604 0.762)
			(layers "F.Cu" "F.Mask" "F.Paste")
			(net "P5V_STBY")
		)
		(pad "2" smd rect
			(at 0.3048 0 90)
			(size 0.6604 0.762)
			(layers "F.Cu" "F.Mask" "F.Paste")
			(net "P5V_STBY_LR")
		)
	)
	(footprint ""
		(layer "F.Cu")
		(at 87.122 -46.609 180)
		(property "Reference" "PC39"
			(at 0 0 180)
			(layer "F.SilkS")
			(hide yes)
			(effects
				(font
					(size 1.27 1.27)
				)
			)
		)
		(property "Value" "SC10U6D3V5KX-4GP"
			(at -0.0762 -6.1214 180)
			(unlocked yes)
			(layer "F.Fab")
			(hide yes)
			(effects
				(font
					(size 1.016 1.016)
					(thickness 0.1524)
				)
			)
		)
		(property "Device Type" "C805H58"
			(at -0.0762 -8.1534 180)
			(unlocked yes)
			(layer "F.Fab")
			(hide yes)
			(effects
				(font
					(size 1.016 1.016)
					(thickness 0.1524)
				)
			)
		)
		(duplicate_pad_numbers_are_jumpers no)
		(fp_line
			(start 0.635 0)
			(end -0.635 0)
			(stroke
				(width 0.508)
				(type default)
			)
			(layer "F.SilkS")
		)
		(fp_rect
			(start -0.9652 1.778)
			(end 0.9652 -1.778)
			(stroke
				(width 0)
				(type default)
			)
			(fill no)
			(layer "F.CrtYd")
		)
		(fp_poly
			(pts
				(xy -0.9652 -1.778) (xy 0.9652 -1.778) (xy 0.9652 1.778) (xy -0.9652 1.778)
			)
			(stroke
				(width 0)
				(type default)
			)
			(fill no)
			(layer "F.Fab")
		)
		(pad "1" smd rect
			(at 0 -0.9652 180)
			(size 1.397 1.143)
			(layers "F.Cu" "F.Mask" "F.Paste")
			(net "P3V3_PWR")
		)
		(pad "2" smd rect
			(at 0 0.9652 180)
			(size 1.397 1.143)
			(layers "F.Cu" "F.Mask" "F.Paste")
			(net "GND")
		)
	)
)
